(kicad_pcb
	(version 20260206)
	(generator "pcbnew")
	(generator_version "10.0")
	(general
		(thickness 1.6)
		(legacy_teardrops no)
	)
	(paper "A4")
	(title_block
		(title "01162023_DA0F0TEBIF0_F0T_Expander_BD_F_brd_V02_OCP.brd")
		(comment 1 "Grand Teton / footprint 6602 of 9728 (PEX1), pads 475-594 of 2397")
	)
	(layers
		(0 "F.Cu" signal "TOP")
		(4 "In1.Cu" signal "GND")
		(6 "In2.Cu" signal "VCC")
		(8 "In3.Cu" signal "VCC1")
		(10 "In4.Cu" signal "GND1")
		(12 "In5.Cu" signal "IN1")
		(14 "In6.Cu" signal "GND2")
		(16 "In7.Cu" signal "IN2")
		(18 "In8.Cu" signal "GND3")
		(20 "In9.Cu" signal "IN3")
		(22 "In10.Cu" signal "GND4")
		(24 "In11.Cu" signal "IN4")
		(26 "In12.Cu" signal "GND5")
		(28 "In13.Cu" signal "IN5")
		(30 "In14.Cu" signal "GND6")
		(32 "In15.Cu" signal "IN6")
		(34 "In16.Cu" signal "GND7")
		(2 "B.Cu" signal "BOTTOM")
		(9 "F.Adhes" user "F.Adhesive")
		(11 "B.Adhes" user "B.Adhesive")
		(13 "F.Paste" user "Package Geometry/Pastemask Top")
		(15 "B.Paste" user "Package Geometry/Pastemask Bottom")
		(5 "F.SilkS" user "Ref Des/Silkscreen Top")
		(7 "B.SilkS" user "Ref Des/Silkscreen Bottom")
		(1 "F.Mask" user "Board Geometry/Soldermask Top")
		(3 "B.Mask" user "Board Geometry/Soldermask Bottom")
		(17 "Dwgs.User" user "User.Drawings")
		(19 "Cmts.User" user "User.Comments")
		(21 "Eco1.User" user "User.Eco1")
		(23 "Eco2.User" user "User.Eco2")
		(25 "Edge.Cuts" user "Board Geometry/Outline")
		(27 "Margin" user)
		(31 "F.CrtYd" user "Package Geometry/Place Bound Top")
		(29 "B.CrtYd" user "Package Geometry/Place Bound Bottom")
		(35 "F.Fab" user "Ref Des/Assembly Top")
		(33 "B.Fab" user "Ref Des/Assembly Bottom")
	)
	(footprint ""
		(layer "F.Cu")
		(at 175.749966 -295.89984)
		(property "Reference" "PEX1"
			(at -3.353562 35.593274 0)
			(unlocked yes)
			(layer "F.SilkS")
			(effects
				(font
					(size 2.032 1.524)
					(thickness 0.1524)
				)
				(justify left)
			)
		)
		(property "Value" ""
			(at 0 0 0)
			(layer "F.Fab")
			(effects
				(font
					(size 1.27 1.27)
				)
			)
		)
		(duplicate_pad_numbers_are_jumpers no)
		(pad "AJ36" smd circle
			(at 10.450068 3.800094)
			(size 0.4572 0.4572)
			(layers "F.Cu" "F.Mask" "F.Paste")
			(net "GND")
		)
		(pad "AJ37" smd circle
			(at 11.400028 3.800094)
			(size 0.4572 0.4572)
			(layers "F.Cu" "F.Mask" "F.Paste")
			(net "GND")
		)
		(pad "AJ38" smd circle
			(at 12.349988 3.800094)
			(size 0.4572 0.4572)
			(layers "F.Cu" "F.Mask" "F.Paste")
			(net "UART_PEX1_CLI_TX")
		)
		(pad "AJ39" smd circle
			(at 13.299948 3.800094)
			(size 0.4572 0.4572)
			(layers "F.Cu" "F.Mask" "F.Paste")
			(net "Net_5238")
		)
		(pad "AJ40" smd circle
			(at 14.249908 3.800094)
			(size 0.4572 0.4572)
			(layers "F.Cu" "F.Mask" "F.Paste")
			(net "GND")
		)
		(pad "AJ41" smd circle
			(at 15.200122 3.800094)
			(size 0.4572 0.4572)
			(layers "F.Cu" "F.Mask" "F.Paste")
			(net "GND")
		)
		(pad "AJ42" smd circle
			(at 16.150082 3.800094)
			(size 0.4572 0.4572)
			(layers "F.Cu" "F.Mask" "F.Paste")
			(net "GND")
		)
		(pad "AJ43" smd circle
			(at 17.100042 3.800094)
			(size 0.4572 0.4572)
			(layers "F.Cu" "F.Mask" "F.Paste")
			(net "Net_1399")
		)
		(pad "AJ44" smd circle
			(at 18.050002 3.800094)
			(size 0.4572 0.4572)
			(layers "F.Cu" "F.Mask" "F.Paste")
			(net "Net_1388")
		)
		(pad "AJ45" smd circle
			(at 18.999962 3.800094)
			(size 0.4572 0.4572)
			(layers "F.Cu" "F.Mask" "F.Paste")
			(net "GND")
		)
		(pad "AJ46" smd circle
			(at 19.949922 3.800094)
			(size 0.4572 0.4572)
			(layers "F.Cu" "F.Mask" "F.Paste")
			(net "Net_1531")
		)
		(pad "AJ47" smd circle
			(at 20.899882 3.800094)
			(size 0.4572 0.4572)
			(layers "F.Cu" "F.Mask" "F.Paste")
			(net "Net_1613")
		)
		(pad "AJ48" smd circle
			(at 21.850096 3.800094)
			(size 0.4572 0.4572)
			(layers "F.Cu" "F.Mask" "F.Paste")
			(net "GND")
		)
		(pad "AJ49" smd circle
			(at 22.800056 3.800094)
			(size 0.4572 0.4572)
			(layers "F.Cu" "F.Mask" "F.Paste")
			(net "GND")
		)
		(pad "AK1" smd circle
			(at -22.800056 4.750054)
			(size 0.4572 0.4572)
			(layers "F.Cu" "F.Mask" "F.Paste")
			(net "GND")
		)
		(pad "AK2" smd circle
			(at -21.850096 4.750054)
			(size 0.4572 0.4572)
			(layers "F.Cu" "F.Mask" "F.Paste")
			(net "GND")
		)
		(pad "AK3" smd circle
			(at -20.899882 4.750054)
			(size 0.4572 0.4572)
			(layers "F.Cu" "F.Mask" "F.Paste")
			(net "GND")
		)
		(pad "AK4" smd circle
			(at -19.949922 4.750054)
			(size 0.4572 0.4572)
			(layers "F.Cu" "F.Mask" "F.Paste")
			(net "Net_501")
		)
		(pad "AK5" smd circle
			(at -18.999962 4.750054)
			(size 0.4572 0.4572)
			(layers "F.Cu" "F.Mask" "F.Paste")
			(net "Net_502")
		)
		(pad "AK6" smd circle
			(at -18.050002 4.750054)
			(size 0.4572 0.4572)
			(layers "F.Cu" "F.Mask" "F.Paste")
			(net "GND")
		)
		(pad "AK7" smd circle
			(at -17.100042 4.750054)
			(size 0.4572 0.4572)
			(layers "F.Cu" "F.Mask" "F.Paste")
			(net "Net_5302")
		)
		(pad "AK8" smd circle
			(at -16.150082 4.750054)
			(size 0.4572 0.4572)
			(layers "F.Cu" "F.Mask" "F.Paste")
			(net "GND")
		)
		(pad "AK9" smd circle
			(at -15.200122 4.750054)
			(size 0.4572 0.4572)
			(layers "F.Cu" "F.Mask" "F.Paste")
			(net "GND")
		)
		(pad "AK10" smd circle
			(at -14.249908 4.750054)
			(size 0.4572 0.4572)
			(layers "F.Cu" "F.Mask" "F.Paste")
			(net "P1V8_PEX")
		)
		(pad "AK11" smd circle
			(at -13.299948 4.750054)
			(size 0.4572 0.4572)
			(layers "F.Cu" "F.Mask" "F.Paste")
			(net "GND")
		)
		(pad "AK12" smd circle
			(at -12.349988 4.750054)
			(size 0.4572 0.4572)
			(layers "F.Cu" "F.Mask" "F.Paste")
			(net "P1V8_PEX")
		)
		(pad "AK13" smd circle
			(at -11.400028 4.750054)
			(size 0.4572 0.4572)
			(layers "F.Cu" "F.Mask" "F.Paste")
			(net "GND")
		)
		(pad "AK14" smd circle
			(at -10.450068 4.750054)
			(size 0.4572 0.4572)
			(layers "F.Cu" "F.Mask" "F.Paste")
			(net "P0V8_PEX1")
		)
		(pad "AK15" smd circle
			(at -9.500108 4.750054)
			(size 0.4572 0.4572)
			(layers "F.Cu" "F.Mask" "F.Paste")
			(net "GND")
		)
		(pad "AK16" smd circle
			(at -8.549894 4.750054)
			(size 0.4572 0.4572)
			(layers "F.Cu" "F.Mask" "F.Paste")
			(net "P0V8_SERDES_VDDA_PEX1")
		)
		(pad "AK17" smd circle
			(at -7.599934 4.750054)
			(size 0.4572 0.4572)
			(layers "F.Cu" "F.Mask" "F.Paste")
			(net "P0V8_SERDES_VDDA_PEX1")
		)
		(pad "AK18" smd circle
			(at -6.649974 4.750054)
			(size 0.4572 0.4572)
			(layers "F.Cu" "F.Mask" "F.Paste")
			(net "P0V8_SERDES_VDDA_PEX1")
		)
		(pad "AK19" smd circle
			(at -5.700014 4.750054)
			(size 0.4572 0.4572)
			(layers "F.Cu" "F.Mask" "F.Paste")
			(net "P0V8_SERDES_VDDA_PEX1")
		)
		(pad "AK20" smd circle
			(at -4.750054 4.750054)
			(size 0.4572 0.4572)
			(layers "F.Cu" "F.Mask" "F.Paste")
			(net "P0V8_SERDES_VDDA_PEX1")
		)
		(pad "AK21" smd circle
			(at -3.800094 4.750054)
			(size 0.4572 0.4572)
			(layers "F.Cu" "F.Mask" "F.Paste")
			(net "P0V8_SERDES_VDDA_PEX1")
		)
		(pad "AK22" smd circle
			(at -2.84988 4.750054)
			(size 0.4572 0.4572)
			(layers "F.Cu" "F.Mask" "F.Paste")
			(net "P0V8_SERDES_VDDA_PEX1")
		)
		(pad "AK23" smd circle
			(at -1.89992 4.750054)
			(size 0.4572 0.4572)
			(layers "F.Cu" "F.Mask" "F.Paste")
			(net "P0V8_SERDES_VDDA_PEX1")
		)
		(pad "AK24" smd circle
			(at -0.94996 4.750054)
			(size 0.4572 0.4572)
			(layers "F.Cu" "F.Mask" "F.Paste")
			(net "P0V8_SERDES_VDDA_PEX1")
		)
		(pad "AK25" smd circle
			(at 0 4.750054)
			(size 0.4572 0.4572)
			(layers "F.Cu" "F.Mask" "F.Paste")
			(net "P0V8_SERDES_VDDA_PEX1")
		)
		(pad "AK26" smd circle
			(at 0.94996 4.750054)
			(size 0.4572 0.4572)
			(layers "F.Cu" "F.Mask" "F.Paste")
			(net "P0V8_SERDES_VDDA_PEX1")
		)
		(pad "AK27" smd circle
			(at 1.89992 4.750054)
			(size 0.4572 0.4572)
			(layers "F.Cu" "F.Mask" "F.Paste")
			(net "P0V8_SERDES_VDDA_PEX1")
		)
		(pad "AK28" smd circle
			(at 2.84988 4.750054)
			(size 0.4572 0.4572)
			(layers "F.Cu" "F.Mask" "F.Paste")
			(net "P0V8_SERDES_VDDA_PEX1")
		)
		(pad "AK29" smd circle
			(at 3.800094 4.750054)
			(size 0.4572 0.4572)
			(layers "F.Cu" "F.Mask" "F.Paste")
			(net "P0V8_SERDES_VDDA_PEX1")
		)
		(pad "AK30" smd circle
			(at 4.750054 4.750054)
			(size 0.4572 0.4572)
			(layers "F.Cu" "F.Mask" "F.Paste")
			(net "P0V8_SERDES_VDDA_PEX1")
		)
		(pad "AK31" smd circle
			(at 5.700014 4.750054)
			(size 0.4572 0.4572)
			(layers "F.Cu" "F.Mask" "F.Paste")
			(net "P0V8_SERDES_VDDA_PEX1")
		)
		(pad "AK32" smd circle
			(at 6.649974 4.750054)
			(size 0.4572 0.4572)
			(layers "F.Cu" "F.Mask" "F.Paste")
			(net "P0V8_SERDES_VDDA_PEX1")
		)
		(pad "AK33" smd circle
			(at 7.599934 4.750054)
			(size 0.4572 0.4572)
			(layers "F.Cu" "F.Mask" "F.Paste")
			(net "P0V8_SERDES_VDDA_PEX1")
		)
		(pad "AK34" smd circle
			(at 8.549894 4.750054)
			(size 0.4572 0.4572)
			(layers "F.Cu" "F.Mask" "F.Paste")
			(net "GND")
		)
		(pad "AK35" smd circle
			(at 9.500108 4.750054)
			(size 0.4572 0.4572)
			(layers "F.Cu" "F.Mask" "F.Paste")
			(net "P1V8_PEX")
		)
		(pad "AK36" smd circle
			(at 10.450068 4.750054)
			(size 0.4572 0.4572)
			(layers "F.Cu" "F.Mask" "F.Paste")
			(net "GND")
		)
		(pad "AK37" smd circle
			(at 11.400028 4.750054)
			(size 0.4572 0.4572)
			(layers "F.Cu" "F.Mask" "F.Paste")
			(net "GND")
		)
		(pad "AK38" smd circle
			(at 12.349988 4.750054)
			(size 0.4572 0.4572)
			(layers "F.Cu" "F.Mask" "F.Paste")
			(net "UART_PEX1_CLI_BUF_RX")
		)
		(pad "AK39" smd circle
			(at 13.299948 4.750054)
			(size 0.4572 0.4572)
			(layers "F.Cu" "F.Mask" "F.Paste")
			(net "UART_PEX1_SDB_BUF_RX")
		)
		(pad "AK40" smd circle
			(at 14.249908 4.750054)
			(size 0.4572 0.4572)
			(layers "F.Cu" "F.Mask" "F.Paste")
			(net "GND")
		)
		(pad "AK41" smd circle
			(at 15.200122 4.750054)
			(size 0.4572 0.4572)
			(layers "F.Cu" "F.Mask" "F.Paste")
			(net "Net_1364")
		)
		(pad "AK42" smd circle
			(at 16.150082 4.750054)
			(size 0.4572 0.4572)
			(layers "F.Cu" "F.Mask" "F.Paste")
			(net "Net_1425")
		)
		(pad "AK43" smd circle
			(at 17.100042 4.750054)
			(size 0.4572 0.4572)
			(layers "F.Cu" "F.Mask" "F.Paste")
			(net "GND")
		)
		(pad "AK44" smd circle
			(at 18.050002 4.750054)
			(size 0.4572 0.4572)
			(layers "F.Cu" "F.Mask" "F.Paste")
			(net "GND")
		)
		(pad "AK45" smd circle
			(at 18.999962 4.750054)
			(size 0.4572 0.4572)
			(layers "F.Cu" "F.Mask" "F.Paste")
			(net "GND")
		)
		(pad "AK46" smd circle
			(at 19.949922 4.750054)
			(size 0.4572 0.4572)
			(layers "F.Cu" "F.Mask" "F.Paste")
			(net "GND")
		)
		(pad "AK47" smd circle
			(at 20.899882 4.750054)
			(size 0.4572 0.4572)
			(layers "F.Cu" "F.Mask" "F.Paste")
			(net "GND")
		)
		(pad "AK48" smd circle
			(at 21.850096 4.750054)
			(size 0.4572 0.4572)
			(layers "F.Cu" "F.Mask" "F.Paste")
			(net "Net_1586")
		)
		(pad "AK49" smd circle
			(at 22.800056 4.750054)
			(size 0.4572 0.4572)
			(layers "F.Cu" "F.Mask" "F.Paste")
			(net "Net_1573")
		)
		(pad "AL1" smd circle
			(at -22.800056 5.700014)
			(size 0.4572 0.4572)
			(layers "F.Cu" "F.Mask" "F.Paste")
			(net "GND")
		)
		(pad "AL2" smd circle
			(at -21.850096 5.700014)
			(size 0.4572 0.4572)
			(layers "F.Cu" "F.Mask" "F.Paste")
			(net "GND")
		)
		(pad "AL3" smd circle
			(at -20.899882 5.700014)
			(size 0.4572 0.4572)
			(layers "F.Cu" "F.Mask" "F.Paste")
			(net "GND")
		)
		(pad "AL4" smd circle
			(at -19.949922 5.700014)
			(size 0.4572 0.4572)
			(layers "F.Cu" "F.Mask" "F.Paste")
			(net "GND")
		)
		(pad "AL5" smd circle
			(at -18.999962 5.700014)
			(size 0.4572 0.4572)
			(layers "F.Cu" "F.Mask" "F.Paste")
			(net "GND")
		)
		(pad "AL6" smd circle
			(at -18.050002 5.700014)
			(size 0.4572 0.4572)
			(layers "F.Cu" "F.Mask" "F.Paste")
			(net "GND")
		)
		(pad "AL7" smd circle
			(at -17.100042 5.700014)
			(size 0.4572 0.4572)
			(layers "F.Cu" "F.Mask" "F.Paste")
			(net "GND")
		)
		(pad "AL8" smd circle
			(at -16.150082 5.700014)
			(size 0.4572 0.4572)
			(layers "F.Cu" "F.Mask" "F.Paste")
			(net "GND")
		)
		(pad "AL9" smd circle
			(at -15.200122 5.700014)
			(size 0.4572 0.4572)
			(layers "F.Cu" "F.Mask" "F.Paste")
			(net "GND")
		)
		(pad "AL10" smd circle
			(at -14.249908 5.700014)
			(size 0.4572 0.4572)
			(layers "F.Cu" "F.Mask" "F.Paste")
			(net "GND")
		)
		(pad "AL11" smd circle
			(at -13.299948 5.700014)
			(size 0.4572 0.4572)
			(layers "F.Cu" "F.Mask" "F.Paste")
			(net "GND")
		)
		(pad "AL12" smd circle
			(at -12.349988 5.700014)
			(size 0.4572 0.4572)
			(layers "F.Cu" "F.Mask" "F.Paste")
			(net "GND")
		)
		(pad "AL13" smd circle
			(at -11.400028 5.700014)
			(size 0.4572 0.4572)
			(layers "F.Cu" "F.Mask" "F.Paste")
			(net "GND")
		)
		(pad "AL14" smd circle
			(at -10.450068 5.700014)
			(size 0.4572 0.4572)
			(layers "F.Cu" "F.Mask" "F.Paste")
			(net "VSSA_SENSE")
		)
		(pad "AL15" smd circle
			(at -9.500108 5.700014)
			(size 0.4572 0.4572)
			(layers "F.Cu" "F.Mask" "F.Paste")
			(net "VDDA_SENSE")
		)
		(pad "AL16" smd circle
			(at -8.549894 5.700014)
			(size 0.4572 0.4572)
			(layers "F.Cu" "F.Mask" "F.Paste")
			(net "GND")
		)
		(pad "AL17" smd circle
			(at -7.599934 5.700014)
			(size 0.4572 0.4572)
			(layers "F.Cu" "F.Mask" "F.Paste")
			(net "GND")
		)
		(pad "AL18" smd circle
			(at -6.649974 5.700014)
			(size 0.4572 0.4572)
			(layers "F.Cu" "F.Mask" "F.Paste")
			(net "GND")
		)
		(pad "AL19" smd circle
			(at -5.700014 5.700014)
			(size 0.4572 0.4572)
			(layers "F.Cu" "F.Mask" "F.Paste")
			(net "GND")
		)
		(pad "AL20" smd circle
			(at -4.750054 5.700014)
			(size 0.4572 0.4572)
			(layers "F.Cu" "F.Mask" "F.Paste")
			(net "GND")
		)
		(pad "AL21" smd circle
			(at -3.800094 5.700014)
			(size 0.4572 0.4572)
			(layers "F.Cu" "F.Mask" "F.Paste")
			(net "GND")
		)
		(pad "AL22" smd circle
			(at -2.84988 5.700014)
			(size 0.4572 0.4572)
			(layers "F.Cu" "F.Mask" "F.Paste")
			(net "GND")
		)
		(pad "AL23" smd circle
			(at -1.89992 5.700014)
			(size 0.4572 0.4572)
			(layers "F.Cu" "F.Mask" "F.Paste")
			(net "GND")
		)
		(pad "AL24" smd circle
			(at -0.94996 5.700014)
			(size 0.4572 0.4572)
			(layers "F.Cu" "F.Mask" "F.Paste")
			(net "GND")
		)
		(pad "AL25" smd circle
			(at 0 5.700014)
			(size 0.4572 0.4572)
			(layers "F.Cu" "F.Mask" "F.Paste")
			(net "GND")
		)
		(pad "AL26" smd circle
			(at 0.94996 5.700014)
			(size 0.4572 0.4572)
			(layers "F.Cu" "F.Mask" "F.Paste")
			(net "GND")
		)
		(pad "AL27" smd circle
			(at 1.89992 5.700014)
			(size 0.4572 0.4572)
			(layers "F.Cu" "F.Mask" "F.Paste")
			(net "GND")
		)
		(pad "AL28" smd circle
			(at 2.84988 5.700014)
			(size 0.4572 0.4572)
			(layers "F.Cu" "F.Mask" "F.Paste")
			(net "GND")
		)
		(pad "AL29" smd circle
			(at 3.800094 5.700014)
			(size 0.4572 0.4572)
			(layers "F.Cu" "F.Mask" "F.Paste")
			(net "GND")
		)
		(pad "AL30" smd circle
			(at 4.750054 5.700014)
			(size 0.4572 0.4572)
			(layers "F.Cu" "F.Mask" "F.Paste")
			(net "GND")
		)
		(pad "AL31" smd circle
			(at 5.700014 5.700014)
			(size 0.4572 0.4572)
			(layers "F.Cu" "F.Mask" "F.Paste")
			(net "GND")
		)
		(pad "AL32" smd circle
			(at 6.649974 5.700014)
			(size 0.4572 0.4572)
			(layers "F.Cu" "F.Mask" "F.Paste")
			(net "GND")
		)
		(pad "AL33" smd circle
			(at 7.599934 5.700014)
			(size 0.4572 0.4572)
			(layers "F.Cu" "F.Mask" "F.Paste")
			(net "GND")
		)
		(pad "AL34" smd circle
			(at 8.549894 5.700014)
			(size 0.4572 0.4572)
			(layers "F.Cu" "F.Mask" "F.Paste")
			(net "GND")
		)
		(pad "AL35" smd circle
			(at 9.500108 5.700014)
			(size 0.4572 0.4572)
			(layers "F.Cu" "F.Mask" "F.Paste")
			(net "P1V8_PEX")
		)
		(pad "AL36" smd circle
			(at 10.450068 5.700014)
			(size 0.4572 0.4572)
			(layers "F.Cu" "F.Mask" "F.Paste")
			(net "GND")
		)
		(pad "AL37" smd circle
			(at 11.400028 5.700014)
			(size 0.4572 0.4572)
			(layers "F.Cu" "F.Mask" "F.Paste")
			(net "GND")
		)
		(pad "AL38" smd circle
			(at 12.349988 5.700014)
			(size 0.4572 0.4572)
			(layers "F.Cu" "F.Mask" "F.Paste")
			(net "Net_5269")
		)
		(pad "AL39" smd circle
			(at 13.299948 5.700014)
			(size 0.4572 0.4572)
			(layers "F.Cu" "F.Mask" "F.Paste")
			(net "UART_PEX1_SDB_TX")
		)
		(pad "AL40" smd circle
			(at 14.249908 5.700014)
			(size 0.4572 0.4572)
			(layers "F.Cu" "F.Mask" "F.Paste")
			(net "GND")
		)
		(pad "AL41" smd circle
			(at 15.200122 5.700014)
			(size 0.4572 0.4572)
			(layers "F.Cu" "F.Mask" "F.Paste")
			(net "GND")
		)
		(pad "AL42" smd circle
			(at 16.150082 5.700014)
			(size 0.4572 0.4572)
			(layers "F.Cu" "F.Mask" "F.Paste")
			(net "GND")
		)
		(pad "AL43" smd circle
			(at 17.100042 5.700014)
			(size 0.4572 0.4572)
			(layers "F.Cu" "F.Mask" "F.Paste")
			(net "Net_1432")
		)
		(pad "AL44" smd circle
			(at 18.050002 5.700014)
			(size 0.4572 0.4572)
			(layers "F.Cu" "F.Mask" "F.Paste")
			(net "Net_1385")
		)
		(pad "AL45" smd circle
			(at 18.999962 5.700014)
			(size 0.4572 0.4572)
			(layers "F.Cu" "F.Mask" "F.Paste")
			(net "GND")
		)
		(pad "AL46" smd circle
			(at 19.949922 5.700014)
			(size 0.4572 0.4572)
			(layers "F.Cu" "F.Mask" "F.Paste")
			(net "Net_1553")
		)
		(pad "AL47" smd circle
			(at 20.899882 5.700014)
			(size 0.4572 0.4572)
			(layers "F.Cu" "F.Mask" "F.Paste")
			(net "Net_1550")
		)
		(pad "AL48" smd circle
			(at 21.850096 5.700014)
			(size 0.4572 0.4572)
			(layers "F.Cu" "F.Mask" "F.Paste")
			(net "GND")
		)
		(pad "AL49" smd circle
			(at 22.800056 5.700014)
			(size 0.4572 0.4572)
			(layers "F.Cu" "F.Mask" "F.Paste")
			(net "GND")
		)
		(pad "AM1" smd circle
			(at -22.800056 6.649974)
			(size 0.4572 0.4572)
			(layers "F.Cu" "F.Mask" "F.Paste")
			(net "Net_1710")
		)
		(pad "AM2" smd circle
			(at -21.850096 6.649974)
			(size 0.4572 0.4572)
			(layers "F.Cu" "F.Mask" "F.Paste")
			(net "Net_1386")
		)
		(pad "AM3" smd circle
			(at -20.899882 6.649974)
			(size 0.4572 0.4572)
			(layers "F.Cu" "F.Mask" "F.Paste")
			(net "GND")
		)
		(pad "AM4" smd circle
			(at -19.949922 6.649974)
			(size 0.4572 0.4572)
			(layers "F.Cu" "F.Mask" "F.Paste")
			(net "GND")
		)
		(pad "AM5" smd circle
			(at -18.999962 6.649974)
			(size 0.4572 0.4572)
			(layers "F.Cu" "F.Mask" "F.Paste")
			(net "GND")
		)
		(pad "AM6" smd circle
			(at -18.050002 6.649974)
			(size 0.4572 0.4572)
			(layers "F.Cu" "F.Mask" "F.Paste")
			(net "GND")
		)
		(pad "AM7" smd circle
			(at -17.100042 6.649974)
			(size 0.4572 0.4572)
			(layers "F.Cu" "F.Mask" "F.Paste")
			(net "GND")
		)
		(pad "AM8" smd circle
			(at -16.150082 6.649974)
			(size 0.4572 0.4572)
			(layers "F.Cu" "F.Mask" "F.Paste")
			(net "Net_1658")
		)
	)
)
